(kicad_pcb
	(version 20260206)
	(generator "pcbnew")
	(generator_version "10.0")
	(general
		(thickness 1.6)
		(legacy_teardrops no)
	)
	(paper "A4")
	(title_block
		(title "15969-1a.1015WZS0858.brd")
		(comment 1 "Tioga Pass / footprints 44-51 of 295")
	)
	(layers
		(0 "F.Cu" signal "TOP")
		(4 "In1.Cu" signal "L2GND")
		(6 "In2.Cu" signal "L3")
		(8 "In3.Cu" signal "L4")
		(10 "In4.Cu" signal "L5GND")
		(2 "B.Cu" signal "BOTTOM")
		(9 "F.Adhes" user "F.Adhesive")
		(11 "B.Adhes" user "B.Adhesive")
		(13 "F.Paste" user "Package Geometry/Pastemask Top")
		(15 "B.Paste" user "Package Geometry/Pastemask Bottom")
		(5 "F.SilkS" user "Ref Des/Silkscreen Top")
		(7 "B.SilkS" user "Ref Des/Silkscreen Bottom")
		(1 "F.Mask" user "Board Geometry/Soldermask Top")
		(3 "B.Mask" user "Board Geometry/Soldermask Bottom")
		(17 "Dwgs.User" user "User.Drawings")
		(19 "Cmts.User" user "User.Comments")
		(21 "Eco1.User" user "User.Eco1")
		(23 "Eco2.User" user "User.Eco2")
		(25 "Edge.Cuts" user "Board Geometry/Outline")
		(27 "Margin" user)
		(31 "F.CrtYd" user "Package Geometry/Place Bound Top")
		(29 "B.CrtYd" user "Package Geometry/Place Bound Bottom")
		(35 "F.Fab" user "Ref Des/Assembly Top")
		(33 "B.Fab" user "Ref Des/Assembly Bottom")
	)
	(footprint ""
		(layer "F.Cu")
		(at 38.6588 -1.8288 90)
		(property "Reference" "C797"
			(at 0 0 90)
			(layer "F.SilkS")
			(hide yes)
			(effects
				(font
					(size 1.27 1.27)
				)
			)
		)
		(property "Value" "SC22U6D3V5MX-5-GP"
			(at -0.0762 -6.1214 90)
			(unlocked yes)
			(layer "F.Fab")
			(hide yes)
			(effects
				(font
					(size 1.016 1.016)
					(thickness 0.1524)
				)
			)
		)
		(property "Device Type" "C805H56"
			(at -0.0762 -8.1534 90)
			(unlocked yes)
			(layer "F.Fab")
			(hide yes)
			(effects
				(font
					(size 1.016 1.016)
					(thickness 0.1524)
				)
			)
		)
		(duplicate_pad_numbers_are_jumpers no)
		(fp_line
			(start 0.635 0)
			(end -0.635 0)
			(stroke
				(width 0.508)
				(type default)
			)
			(layer "F.SilkS")
		)
		(fp_rect
			(start -0.9652 1.778)
			(end 0.9652 -1.778)
			(stroke
				(width 0)
				(type default)
			)
			(fill no)
			(layer "F.CrtYd")
		)
		(fp_poly
			(pts
				(xy -0.9652 -1.778) (xy 0.9652 -1.778) (xy 0.9652 1.778) (xy -0.9652 1.778)
			)
			(stroke
				(width 0)
				(type default)
			)
			(fill no)
			(layer "F.Fab")
		)
		(pad "1" smd rect
			(at 0 -0.9652 90)
			(size 1.397 1.143)
			(layers "F.Cu" "F.Mask" "F.Paste")
			(net "P3V3")
		)
		(pad "2" smd rect
			(at 0 0.9652 90)
			(size 1.397 1.143)
			(layers "F.Cu" "F.Mask" "F.Paste")
			(net "GND")
		)
	)
	(footprint ""
		(layer "F.Cu")
		(at 118.8212 -31.2674 90)
		(property "Reference" "RU27"
			(at 0 0 90)
			(layer "F.SilkS")
			(hide yes)
			(effects
				(font
					(size 1.27 1.27)
				)
			)
		)
		(property "Value" "10KR2F-2-GP"
			(at 0.064008 -3.993896 90)
			(unlocked yes)
			(layer "F.Fab")
			(hide yes)
			(effects
				(font
					(size 1.016 1.016)
					(thickness 0.1524)
				)
			)
		)
		(property "Device Type" "R402H16"
			(at 0.064008 -5.517896 90)
			(unlocked yes)
			(layer "F.Fab")
			(hide yes)
			(effects
				(font
					(size 1.016 1.016)
					(thickness 0.1524)
				)
			)
		)
		(duplicate_pad_numbers_are_jumpers no)
		(fp_line
			(start 0.508 -0.9398)
			(end -0.508 -0.9398)
			(stroke
				(width 0.1524)
				(type default)
			)
			(layer "F.SilkS")
		)
		(fp_line
			(start -0.508 -0.9398)
			(end -0.508 0.9398)
			(stroke
				(width 0.1524)
				(type default)
			)
			(layer "F.SilkS")
		)
		(fp_rect
			(start -0.508 0.9398)
			(end 0.508 -0.9398)
			(stroke
				(width 0)
				(type default)
			)
			(fill no)
			(layer "F.CrtYd")
		)
		(fp_rect
			(start -0.508 0.9398)
			(end 0.508 -0.9398)
			(stroke
				(width 0)
				(type default)
			)
			(fill no)
			(layer "F.Fab")
		)
		(pad "1" smd custom
			(at 0 -0.4445 90)
			(size 0.1397 0.1397)
			(layers "F.Cu" "F.Mask" "F.Paste")
			(net "P3V3_USB_HUB")
			(options
				(clearance outline)
				(anchor circle)
			)
			(primitives
				(gr_poly
					(pts
						(arc
							(start -0.1778 -0.2794)
							(mid -0.249642 -0.249642)
							(end -0.2794 -0.1778)
						)
						(arc
							(start -0.2794 0.1778)
							(mid -0.249642 0.249642)
							(end -0.1778 0.2794)
						)
						(arc
							(start 0.1778 0.2794)
							(mid 0.249642 0.249642)
							(end 0.2794 0.1778)
						)
						(arc
							(start 0.2794 -0.1778)
							(mid 0.249642 -0.249642)
							(end 0.1778 -0.2794)
						)
					)
					(width 0)
					(fill yes)
				)
			)
		)
		(pad "2" smd custom
			(at 0 0.4445 90)
			(size 0.1397 0.1397)
			(layers "F.Cu" "F.Mask" "F.Paste")
			(net "TP_USB_DN3")
			(options
				(clearance outline)
				(anchor circle)
			)
			(primitives
				(gr_poly
					(pts
						(arc
							(start -0.1778 -0.2794)
							(mid -0.249642 -0.249642)
							(end -0.2794 -0.1778)
						)
						(arc
							(start -0.2794 0.1778)
							(mid -0.249642 0.249642)
							(end -0.1778 0.2794)
						)
						(arc
							(start 0.1778 0.2794)
							(mid 0.249642 0.249642)
							(end 0.2794 0.1778)
						)
						(arc
							(start 0.2794 -0.1778)
							(mid 0.249642 -0.249642)
							(end 0.1778 -0.2794)
						)
					)
					(width 0)
					(fill yes)
				)
			)
		)
	)
	(footprint ""
		(layer "F.Cu")
		(at 130.2512 -10.7696)
		(property "Reference" "R121"
			(at 0 0 0)
			(layer "F.SilkS")
			(hide yes)
			(effects
				(font
					(size 1.27 1.27)
				)
			)
		)
		(property "Value" "10KR2F-2-GP"
			(at 0.064008 -3.993896 0)
			(unlocked yes)
			(layer "F.Fab")
			(hide yes)
			(effects
				(font
					(size 1.016 1.016)
					(thickness 0.1524)
				)
			)
		)
		(property "Device Type" "R402H16"
			(at 0.064008 -5.517896 0)
			(unlocked yes)
			(layer "F.Fab")
			(hide yes)
			(effects
				(font
					(size 1.016 1.016)
					(thickness 0.1524)
				)
			)
		)
		(duplicate_pad_numbers_are_jumpers no)
		(fp_line
			(start -0.508 -0.9398)
			(end -0.508 0.9398)
			(stroke
				(width 0.1524)
				(type default)
			)
			(layer "F.SilkS")
		)
		(fp_line
			(start 0.508 -0.9398)
			(end -0.508 -0.9398)
			(stroke
				(width 0.1524)
				(type default)
			)
			(layer "F.SilkS")
		)
		(fp_rect
			(start -0.508 0.9398)
			(end 0.508 -0.9398)
			(stroke
				(width 0)
				(type default)
			)
			(fill no)
			(layer "F.CrtYd")
		)
		(fp_rect
			(start -0.508 0.9398)
			(end 0.508 -0.9398)
			(stroke
				(width 0)
				(type default)
			)
			(fill no)
			(layer "F.Fab")
		)
		(pad "1" smd custom
			(at 0 -0.4445)
			(size 0.1397 0.1397)
			(layers "F.Cu" "F.Mask" "F.Paste")
			(net "GPIO_B_IO1_0")
			(options
				(clearance outline)
				(anchor circle)
			)
			(primitives
				(gr_poly
					(pts
						(arc
							(start -0.1778 -0.2794)
							(mid -0.249642 -0.249642)
							(end -0.2794 -0.1778)
						)
						(arc
							(start -0.2794 0.1778)
							(mid -0.249642 0.249642)
							(end -0.1778 0.2794)
						)
						(arc
							(start 0.1778 0.2794)
							(mid 0.249642 0.249642)
							(end 0.2794 0.1778)
						)
						(arc
							(start 0.2794 -0.1778)
							(mid 0.249642 -0.249642)
							(end 0.1778 -0.2794)
						)
					)
					(width 0)
					(fill yes)
				)
			)
		)
		(pad "2" smd custom
			(at 0 0.4445)
			(size 0.1397 0.1397)
			(layers "F.Cu" "F.Mask" "F.Paste")
			(net "GND")
			(options
				(clearance outline)
				(anchor circle)
			)
			(primitives
				(gr_poly
					(pts
						(arc
							(start -0.1778 -0.2794)
							(mid -0.249642 -0.249642)
							(end -0.2794 -0.1778)
						)
						(arc
							(start -0.2794 0.1778)
							(mid -0.249642 0.249642)
							(end -0.1778 0.2794)
						)
						(arc
							(start 0.1778 0.2794)
							(mid 0.249642 0.249642)
							(end 0.2794 0.1778)
						)
						(arc
							(start 0.2794 -0.1778)
							(mid 0.249642 -0.249642)
							(end 0.1778 -0.2794)
						)
					)
					(width 0)
					(fill yes)
				)
			)
		)
	)
	(footprint ""
		(layer "F.Cu")
		(at 126.4412 0.1524 90)
		(property "Reference" "R154"
			(at 0 0 90)
			(layer "F.SilkS")
			(hide yes)
			(effects
				(font
					(size 1.27 1.27)
				)
			)
		)
		(property "Value" "10KR2F-2-GP"
			(at 0.064008 -3.993896 90)
			(unlocked yes)
			(layer "F.Fab")
			(hide yes)
			(effects
				(font
					(size 1.016 1.016)
					(thickness 0.1524)
				)
			)
		)
		(property "Device Type" "R402H16"
			(at 0.064008 -5.517896 90)
			(unlocked yes)
			(layer "F.Fab")
			(hide yes)
			(effects
				(font
					(size 1.016 1.016)
					(thickness 0.1524)
				)
			)
		)
		(duplicate_pad_numbers_are_jumpers no)
		(fp_line
			(start 0.508 -0.9398)
			(end -0.508 -0.9398)
			(stroke
				(width 0.1524)
				(type default)
			)
			(layer "F.SilkS")
		)
		(fp_line
			(start -0.508 -0.9398)
			(end -0.508 0.9398)
			(stroke
				(width 0.1524)
				(type default)
			)
			(layer "F.SilkS")
		)
		(fp_rect
			(start -0.508 0.9398)
			(end 0.508 -0.9398)
			(stroke
				(width 0)
				(type default)
			)
			(fill no)
			(layer "F.CrtYd")
		)
		(fp_rect
			(start -0.508 0.9398)
			(end 0.508 -0.9398)
			(stroke
				(width 0)
				(type default)
			)
			(fill no)
			(layer "F.Fab")
		)
		(pad "1" smd custom
			(at 0 -0.4445 90)
			(size 0.1397 0.1397)
			(layers "F.Cu" "F.Mask" "F.Paste")
			(net "GPIO_P_IO1_7")
			(options
				(clearance outline)
				(anchor circle)
			)
			(primitives
				(gr_poly
					(pts
						(arc
							(start -0.1778 -0.2794)
							(mid -0.249642 -0.249642)
							(end -0.2794 -0.1778)
						)
						(arc
							(start -0.2794 0.1778)
							(mid -0.249642 0.249642)
							(end -0.1778 0.2794)
						)
						(arc
							(start 0.1778 0.2794)
							(mid 0.249642 0.249642)
							(end 0.2794 0.1778)
						)
						(arc
							(start 0.2794 -0.1778)
							(mid 0.249642 -0.249642)
							(end 0.1778 -0.2794)
						)
					)
					(width 0)
					(fill yes)
				)
			)
		)
		(pad "2" smd custom
			(at 0 0.4445 90)
			(size 0.1397 0.1397)
			(layers "F.Cu" "F.Mask" "F.Paste")
			(net "GND")
			(options
				(clearance outline)
				(anchor circle)
			)
			(primitives
				(gr_poly
					(pts
						(arc
							(start -0.1778 -0.2794)
							(mid -0.249642 -0.249642)
							(end -0.2794 -0.1778)
						)
						(arc
							(start -0.2794 0.1778)
							(mid -0.249642 0.249642)
							(end -0.1778 0.2794)
						)
						(arc
							(start 0.1778 0.2794)
							(mid 0.249642 0.249642)
							(end 0.2794 0.1778)
						)
						(arc
							(start 0.2794 -0.1778)
							(mid 0.249642 -0.249642)
							(end 0.1778 -0.2794)
						)
					)
					(width 0)
					(fill yes)
				)
			)
		)
	)
	(footprint ""
		(layer "F.Cu")
		(at 98.5012 -18.8214 180)
		(property "Reference" "R98"
			(at 0 0 180)
			(layer "F.SilkS")
			(hide yes)
			(effects
				(font
					(size 1.27 1.27)
				)
			)
		)
		(property "Value" "0R2F-1-GP"
			(at 0.064008 -3.993896 180)
			(unlocked yes)
			(layer "F.Fab")
			(hide yes)
			(effects
				(font
					(size 1.016 1.016)
					(thickness 0.1524)
				)
			)
		)
		(property "Device Type" "R402H16"
			(at 0.064008 -5.517896 180)
			(unlocked yes)
			(layer "F.Fab")
			(hide yes)
			(effects
				(font
					(size 1.016 1.016)
					(thickness 0.1524)
				)
			)
		)
		(duplicate_pad_numbers_are_jumpers no)
		(fp_line
			(start 0.508 -0.9398)
			(end -0.508 -0.9398)
			(stroke
				(width 0.1524)
				(type default)
			)
			(layer "F.SilkS")
		)
		(fp_line
			(start -0.508 -0.9398)
			(end -0.508 0.9398)
			(stroke
				(width 0.1524)
				(type default)
			)
			(layer "F.SilkS")
		)
		(fp_rect
			(start -0.508 0.9398)
			(end 0.508 -0.9398)
			(stroke
				(width 0)
				(type default)
			)
			(fill no)
			(layer "F.CrtYd")
		)
		(fp_rect
			(start -0.508 0.9398)
			(end 0.508 -0.9398)
			(stroke
				(width 0)
				(type default)
			)
			(fill no)
			(layer "F.Fab")
		)
		(pad "1" smd custom
			(at 0 -0.4445 180)
			(size 0.1397 0.1397)
			(layers "F.Cu" "F.Mask" "F.Paste")
			(net "P3V3_PG")
			(options
				(clearance outline)
				(anchor circle)
			)
			(primitives
				(gr_poly
					(pts
						(arc
							(start -0.1778 -0.2794)
							(mid -0.249642 -0.249642)
							(end -0.2794 -0.1778)
						)
						(arc
							(start -0.2794 0.1778)
							(mid -0.249642 0.249642)
							(end -0.1778 0.2794)
						)
						(arc
							(start 0.1778 0.2794)
							(mid 0.249642 0.249642)
							(end 0.2794 0.1778)
						)
						(arc
							(start 0.2794 -0.1778)
							(mid 0.249642 -0.249642)
							(end 0.1778 -0.2794)
						)
					)
					(width 0)
					(fill yes)
				)
			)
		)
		(pad "2" smd custom
			(at 0 0.4445 180)
			(size 0.1397 0.1397)
			(layers "F.Cu" "F.Mask" "F.Paste")
			(net "RESET_O_2_R")
			(options
				(clearance outline)
				(anchor circle)
			)
			(primitives
				(gr_poly
					(pts
						(arc
							(start -0.1778 -0.2794)
							(mid -0.249642 -0.249642)
							(end -0.2794 -0.1778)
						)
						(arc
							(start -0.2794 0.1778)
							(mid -0.249642 0.249642)
							(end -0.1778 0.2794)
						)
						(arc
							(start 0.1778 0.2794)
							(mid 0.249642 0.249642)
							(end 0.2794 0.1778)
						)
						(arc
							(start 0.2794 -0.1778)
							(mid 0.249642 -0.249642)
							(end 0.1778 -0.2794)
						)
					)
					(width 0)
					(fill yes)
				)
			)
		)
	)
	(footprint ""
		(layer "F.Cu")
		(at 99.3902 5.0038 90)
		(property "Reference" "R119"
			(at 0 0 90)
			(layer "F.SilkS")
			(hide yes)
			(effects
				(font
					(size 1.27 1.27)
				)
			)
		)
		(property "Value" "100R2F-L1-GP-U"
			(at 0.064008 -3.993896 90)
			(unlocked yes)
			(layer "F.Fab")
			(hide yes)
			(effects
				(font
					(size 1.016 1.016)
					(thickness 0.1524)
				)
			)
		)
		(property "Device Type" "R402H14"
			(at 0.064008 -5.517896 90)
			(unlocked yes)
			(layer "F.Fab")
			(hide yes)
			(effects
				(font
					(size 1.016 1.016)
					(thickness 0.1524)
				)
			)
		)
		(duplicate_pad_numbers_are_jumpers no)
		(fp_line
			(start 0.508 -0.9398)
			(end -0.508 -0.9398)
			(stroke
				(width 0.1524)
				(type default)
			)
			(layer "F.SilkS")
		)
		(fp_line
			(start -0.508 -0.9398)
			(end -0.508 0.9398)
			(stroke
				(width 0.1524)
				(type default)
			)
			(layer "F.SilkS")
		)
		(fp_rect
			(start -0.508 0.9398)
			(end 0.508 -0.9398)
			(stroke
				(width 0)
				(type default)
			)
			(fill no)
			(layer "F.CrtYd")
		)
		(fp_rect
			(start -0.508 0.9398)
			(end 0.508 -0.9398)
			(stroke
				(width 0)
				(type default)
			)
			(fill no)
			(layer "F.Fab")
		)
		(pad "1" smd custom
			(at 0 -0.4445 90)
			(size 0.1397 0.1397)
			(layers "F.Cu" "F.Mask" "F.Paste")
			(net "FM_PRSNT_2_6_N")
			(options
				(clearance outline)
				(anchor circle)
			)
			(primitives
				(gr_poly
					(pts
						(arc
							(start -0.1778 -0.2794)
							(mid -0.249642 -0.249642)
							(end -0.2794 -0.1778)
						)
						(arc
							(start -0.2794 0.1778)
							(mid -0.249642 0.249642)
							(end -0.1778 0.2794)
						)
						(arc
							(start 0.1778 0.2794)
							(mid 0.249642 0.249642)
							(end 0.2794 0.1778)
						)
						(arc
							(start 0.2794 -0.1778)
							(mid 0.249642 -0.249642)
							(end 0.1778 -0.2794)
						)
					)
					(width 0)
					(fill yes)
				)
			)
		)
		(pad "2" smd custom
			(at 0 0.4445 90)
			(size 0.1397 0.1397)
			(layers "F.Cu" "F.Mask" "F.Paste")
			(net "GND")
			(options
				(clearance outline)
				(anchor circle)
			)
			(primitives
				(gr_poly
					(pts
						(arc
							(start -0.1778 -0.2794)
							(mid -0.249642 -0.249642)
							(end -0.2794 -0.1778)
						)
						(arc
							(start -0.2794 0.1778)
							(mid -0.249642 0.249642)
							(end -0.1778 0.2794)
						)
						(arc
							(start 0.1778 0.2794)
							(mid 0.249642 0.249642)
							(end 0.2794 0.1778)
						)
						(arc
							(start 0.2794 -0.1778)
							(mid 0.249642 -0.249642)
							(end 0.1778 -0.2794)
						)
					)
					(width 0)
					(fill yes)
				)
			)
		)
	)
	(footprint ""
		(layer "F.Cu")
		(at 119.1514 -19.1516 -90)
		(property "Reference" "R117"
			(at 0 0 270)
			(layer "F.SilkS")
			(hide yes)
			(effects
				(font
					(size 1.27 1.27)
				)
			)
		)
		(property "Value" "10KR2F-2-GP"
			(at 0.064008 -3.993896 270)
			(unlocked yes)
			(layer "F.Fab")
			(hide yes)
			(effects
				(font
					(size 1.016 1.016)
					(thickness 0.1524)
				)
			)
		)
		(property "Device Type" "R402H16"
			(at 0.064008 -5.517896 270)
			(unlocked yes)
			(layer "F.Fab")
			(hide yes)
			(effects
				(font
					(size 1.016 1.016)
					(thickness 0.1524)
				)
			)
		)
		(duplicate_pad_numbers_are_jumpers no)
		(fp_line
			(start -0.508 -0.9398)
			(end -0.508 0.9398)
			(stroke
				(width 0.1524)
				(type default)
			)
			(layer "F.SilkS")
		)
		(fp_line
			(start 0.508 -0.9398)
			(end -0.508 -0.9398)
			(stroke
				(width 0.1524)
				(type default)
			)
			(layer "F.SilkS")
		)
		(fp_rect
			(start -0.508 0.9398)
			(end 0.508 -0.9398)
			(stroke
				(width 0)
				(type default)
			)
			(fill no)
			(layer "F.CrtYd")
		)
		(fp_rect
			(start -0.508 0.9398)
			(end 0.508 -0.9398)
			(stroke
				(width 0)
				(type default)
			)
			(fill no)
			(layer "F.Fab")
		)
		(pad "1" smd custom
			(at 0 -0.4445 270)
			(size 0.1397 0.1397)
			(layers "F.Cu" "F.Mask" "F.Paste")
			(net "GPIO_B_EXP_A1")
			(options
				(clearance outline)
				(anchor circle)
			)
			(primitives
				(gr_poly
					(pts
						(arc
							(start -0.1778 -0.2794)
							(mid -0.249642 -0.249642)
							(end -0.2794 -0.1778)
						)
						(arc
							(start -0.2794 0.1778)
							(mid -0.249642 0.249642)
							(end -0.1778 0.2794)
						)
						(arc
							(start 0.1778 0.2794)
							(mid 0.249642 0.249642)
							(end 0.2794 0.1778)
						)
						(arc
							(start 0.2794 -0.1778)
							(mid 0.249642 -0.249642)
							(end 0.1778 -0.2794)
						)
					)
					(width 0)
					(fill yes)
				)
			)
		)
		(pad "2" smd custom
			(at 0 0.4445 270)
			(size 0.1397 0.1397)
			(layers "F.Cu" "F.Mask" "F.Paste")
			(net "GND")
			(options
				(clearance outline)
				(anchor circle)
			)
			(primitives
				(gr_poly
					(pts
						(arc
							(start -0.1778 -0.2794)
							(mid -0.249642 -0.249642)
							(end -0.2794 -0.1778)
						)
						(arc
							(start -0.2794 0.1778)
							(mid -0.249642 0.249642)
							(end -0.1778 0.2794)
						)
						(arc
							(start 0.1778 0.2794)
							(mid 0.249642 0.249642)
							(end 0.2794 0.1778)
						)
						(arc
							(start 0.2794 -0.1778)
							(mid 0.249642 -0.249642)
							(end 0.1778 -0.2794)
						)
					)
					(width 0)
					(fill yes)
				)
			)
		)
	)
	(footprint ""
		(layer "F.Cu")
		(at 119.5832 -5.9944 -90)
		(property "Reference" "R138"
			(at 0 0 270)
			(layer "F.SilkS")
			(hide yes)
			(effects
				(font
					(size 1.27 1.27)
				)
			)
		)
		(property "Value" "10KR2F-2-GP"
			(at 0.064008 -3.993896 270)
			(unlocked yes)
			(layer "F.Fab")
			(hide yes)
			(effects
				(font
					(size 1.016 1.016)
					(thickness 0.1524)
				)
			)
		)
		(property "Device Type" "R402H16"
			(at 0.064008 -5.517896 270)
			(unlocked yes)
			(layer "F.Fab")
			(hide yes)
			(effects
				(font
					(size 1.016 1.016)
					(thickness 0.1524)
				)
			)
		)
		(duplicate_pad_numbers_are_jumpers no)
		(fp_line
			(start -0.508 -0.9398)
			(end -0.508 0.9398)
			(stroke
				(width 0.1524)
				(type default)
			)
			(layer "F.SilkS")
		)
		(fp_line
			(start 0.508 -0.9398)
			(end -0.508 -0.9398)
			(stroke
				(width 0.1524)
				(type default)
			)
			(layer "F.SilkS")
		)
		(fp_rect
			(start -0.508 0.9398)
			(end 0.508 -0.9398)
			(stroke
				(width 0)
				(type default)
			)
			(fill no)
			(layer "F.CrtYd")
		)
		(fp_rect
			(start -0.508 0.9398)
			(end 0.508 -0.9398)
			(stroke
				(width 0)
				(type default)
			)
			(fill no)
			(layer "F.Fab")
		)
		(pad "1" smd custom
			(at 0 -0.4445 270)
			(size 0.1397 0.1397)
			(layers "F.Cu" "F.Mask" "F.Paste")
			(net "GPIO_P_IO1_4")
			(options
				(clearance outline)
				(anchor circle)
			)
			(primitives
				(gr_poly
					(pts
						(arc
							(start -0.1778 -0.2794)
							(mid -0.249642 -0.249642)
							(end -0.2794 -0.1778)
						)
						(arc
							(start -0.2794 0.1778)
							(mid -0.249642 0.249642)
							(end -0.1778 0.2794)
						)
						(arc
							(start 0.1778 0.2794)
							(mid 0.249642 0.249642)
							(end 0.2794 0.1778)
						)
						(arc
							(start 0.2794 -0.1778)
							(mid 0.249642 -0.249642)
							(end 0.1778 -0.2794)
						)
					)
					(width 0)
					(fill yes)
				)
			)
		)
		(pad "2" smd custom
			(at 0 0.4445 270)
			(size 0.1397 0.1397)
			(layers "F.Cu" "F.Mask" "F.Paste")
			(net "GND")
			(options
				(clearance outline)
				(anchor circle)
			)
			(primitives
				(gr_poly
					(pts
						(arc
							(start -0.1778 -0.2794)
							(mid -0.249642 -0.249642)
							(end -0.2794 -0.1778)
						)
						(arc
							(start -0.2794 0.1778)
							(mid -0.249642 0.249642)
							(end -0.1778 0.2794)
						)
						(arc
							(start 0.1778 0.2794)
							(mid 0.249642 0.249642)
							(end 0.2794 0.1778)
						)
						(arc
							(start 0.2794 -0.1778)
							(mid 0.249642 -0.249642)
							(end 0.1778 -0.2794)
						)
					)
					(width 0)
					(fill yes)
				)
			)
		)
	)
)
